(kicad_pcb
	(version 20260206)
	(generator "pcbnew")
	(generator_version "10.0")
	(general
		(thickness 1.6)
		(legacy_teardrops no)
	)
	(paper "A4")
	(title_block
		(title "12092022_DA0F0TFB6D0_F0T_FAN_BOARD_MP5048_D_brd_v02_OCP.brd")
		(comment 1 "Grand Teton / footprints 116-121 of 924")
	)
	(layers
		(0 "F.Cu" signal "TOP")
		(4 "In1.Cu" signal "GND")
		(6 "In2.Cu" signal "IN1")
		(8 "In3.Cu" signal "IN2")
		(10 "In4.Cu" signal "GND1")
		(2 "B.Cu" signal "BOTTOM")
		(9 "F.Adhes" user "F.Adhesive")
		(11 "B.Adhes" user "B.Adhesive")
		(13 "F.Paste" user "Package Geometry/Pastemask Top")
		(15 "B.Paste" user "Package Geometry/Pastemask Bottom")
		(5 "F.SilkS" user "Ref Des/Silkscreen Top")
		(7 "B.SilkS" user "Ref Des/Silkscreen Bottom")
		(1 "F.Mask" user "Board Geometry/Soldermask Top")
		(3 "B.Mask" user "Board Geometry/Soldermask Bottom")
		(17 "Dwgs.User" user "User.Drawings")
		(19 "Cmts.User" user "User.Comments")
		(21 "Eco1.User" user "User.Eco1")
		(23 "Eco2.User" user "User.Eco2")
		(25 "Edge.Cuts" user "Board Geometry/Outline")
		(27 "Margin" user)
		(31 "F.CrtYd" user "Package Geometry/Place Bound Top")
		(29 "B.CrtYd" user "Package Geometry/Place Bound Bottom")
		(35 "F.Fab" user "Ref Des/Assembly Top")
		(33 "B.Fab" user "Ref Des/Assembly Bottom")
	)
	(footprint ""
		(layer "F.Cu")
		(at 47.752 -308.61 180)
		(property "Reference" "C2019"
			(at 0 0 180)
			(layer "F.SilkS")
			(hide yes)
			(effects
				(font
					(size 1.27 1.27)
				)
			)
		)
		(property "Value" ""
			(at 0 0 180)
			(layer "F.Fab")
			(effects
				(font
					(size 1.27 1.27)
				)
			)
		)
		(duplicate_pad_numbers_are_jumpers no)
		(fp_line
			(start 0.7874 0.4064)
			(end -0.7874 0.4064)
			(stroke
				(width 0.1524)
				(type default)
			)
			(layer "F.SilkS")
		)
		(fp_line
			(start 0.7874 -0.4064)
			(end 0.7874 0.4064)
			(stroke
				(width 0.1524)
				(type default)
			)
			(layer "F.SilkS")
		)
		(fp_line
			(start -0.7874 0.4064)
			(end -0.7874 -0.4064)
			(stroke
				(width 0.1524)
				(type default)
			)
			(layer "F.SilkS")
		)
		(fp_line
			(start -0.7874 -0.4064)
			(end 0.7874 -0.4064)
			(stroke
				(width 0.1524)
				(type default)
			)
			(layer "F.SilkS")
		)
		(fp_line
			(start 0.6858 0.3048)
			(end 0.1016 0.3048)
			(stroke
				(width 0.1)
				(type default)
			)
			(layer "F.Fab")
		)
		(fp_line
			(start 0.6858 -0.3048)
			(end 0.6858 0.3048)
			(stroke
				(width 0.1)
				(type default)
			)
			(layer "F.Fab")
		)
		(fp_line
			(start 0.1016 0.3048)
			(end 0.1016 0.2794)
			(stroke
				(width 0.1)
				(type default)
			)
			(layer "F.Fab")
		)
		(fp_line
			(start 0.1016 0.2794)
			(end -0.1016 0.2794)
			(stroke
				(width 0.1)
				(type default)
			)
			(layer "F.Fab")
		)
		(fp_line
			(start 0.1016 -0.2794)
			(end 0.1016 -0.3048)
			(stroke
				(width 0.1)
				(type default)
			)
			(layer "F.Fab")
		)
		(fp_line
			(start 0.1016 -0.3048)
			(end 0.6858 -0.3048)
			(stroke
				(width 0.1)
				(type default)
			)
			(layer "F.Fab")
		)
		(fp_line
			(start -0.1016 0.3048)
			(end -0.6858 0.3048)
			(stroke
				(width 0.1)
				(type default)
			)
			(layer "F.Fab")
		)
		(fp_line
			(start -0.1016 0.2794)
			(end -0.1016 0.3048)
			(stroke
				(width 0.1)
				(type default)
			)
			(layer "F.Fab")
		)
		(fp_line
			(start -0.1016 -0.2794)
			(end 0.1016 -0.2794)
			(stroke
				(width 0.1)
				(type default)
			)
			(layer "F.Fab")
		)
		(fp_line
			(start -0.1016 -0.3048)
			(end -0.1016 -0.2794)
			(stroke
				(width 0.1)
				(type default)
			)
			(layer "F.Fab")
		)
		(fp_line
			(start -0.6858 0.3048)
			(end -0.6858 -0.3048)
			(stroke
				(width 0.1)
				(type default)
			)
			(layer "F.Fab")
		)
		(fp_line
			(start -0.6858 -0.3048)
			(end -0.1016 -0.3048)
			(stroke
				(width 0.1)
				(type default)
			)
			(layer "F.Fab")
		)
		(pad "1" smd rect
			(at -0.40005 0)
			(size 0.4572 0.508)
			(layers "F.Cu" "F.Mask" "F.Paste")
			(net "GND")
		)
		(pad "2" smd rect
			(at 0.40005 0)
			(size 0.4572 0.508)
			(layers "F.Cu" "F.Mask" "F.Paste")
			(net "P12V_LED_FAN0")
		)
	)
	(footprint ""
		(layer "F.Cu")
		(at 34.666428 -67.494912 90)
		(property "Reference" "C165"
			(at 0 0 90)
			(layer "F.SilkS")
			(hide yes)
			(effects
				(font
					(size 1.27 1.27)
				)
			)
		)
		(property "Value" ""
			(at 0 0 90)
			(layer "F.Fab")
			(effects
				(font
					(size 1.27 1.27)
				)
			)
		)
		(duplicate_pad_numbers_are_jumpers no)
		(fp_line
			(start 0.7874 -0.4064)
			(end 0.7874 0.4064)
			(stroke
				(width 0.1524)
				(type default)
			)
			(layer "F.SilkS")
		)
		(fp_line
			(start -0.7874 -0.4064)
			(end 0.7874 -0.4064)
			(stroke
				(width 0.1524)
				(type default)
			)
			(layer "F.SilkS")
		)
		(fp_line
			(start 0.7874 0.4064)
			(end -0.7874 0.4064)
			(stroke
				(width 0.1524)
				(type default)
			)
			(layer "F.SilkS")
		)
		(fp_line
			(start -0.7874 0.4064)
			(end -0.7874 -0.4064)
			(stroke
				(width 0.1524)
				(type default)
			)
			(layer "F.SilkS")
		)
		(fp_line
			(start -0.12065 -0.305054)
			(end -0.12065 -0.2794)
			(stroke
				(width 0.1)
				(type default)
			)
			(layer "F.Fab")
		)
		(fp_line
			(start -0.67945 -0.305054)
			(end -0.12065 -0.305054)
			(stroke
				(width 0.1)
				(type default)
			)
			(layer "F.Fab")
		)
		(fp_line
			(start 0.67945 -0.3048)
			(end 0.67945 0.3048)
			(stroke
				(width 0.1)
				(type default)
			)
			(layer "F.Fab")
		)
		(fp_line
			(start 0.12065 -0.3048)
			(end 0.67945 -0.3048)
			(stroke
				(width 0.1)
				(type default)
			)
			(layer "F.Fab")
		)
		(fp_line
			(start 0.12065 -0.2794)
			(end 0.12065 -0.3048)
			(stroke
				(width 0.1)
				(type default)
			)
			(layer "F.Fab")
		)
		(fp_line
			(start -0.12065 -0.2794)
			(end 0.12065 -0.2794)
			(stroke
				(width 0.1)
				(type default)
			)
			(layer "F.Fab")
		)
		(fp_line
			(start 0.120396 0.2794)
			(end -0.12065 0.2794)
			(stroke
				(width 0.1)
				(type default)
			)
			(layer "F.Fab")
		)
		(fp_line
			(start -0.12065 0.2794)
			(end -0.12065 0.3048)
			(stroke
				(width 0.1)
				(type default)
			)
			(layer "F.Fab")
		)
		(fp_line
			(start 0.67945 0.3048)
			(end 0.120396 0.3048)
			(stroke
				(width 0.1)
				(type default)
			)
			(layer "F.Fab")
		)
		(fp_line
			(start 0.120396 0.3048)
			(end 0.120396 0.2794)
			(stroke
				(width 0.1)
				(type default)
			)
			(layer "F.Fab")
		)
		(fp_line
			(start -0.12065 0.3048)
			(end -0.67945 0.3048)
			(stroke
				(width 0.1)
				(type default)
			)
			(layer "F.Fab")
		)
		(fp_line
			(start -0.67945 0.3048)
			(end -0.67945 -0.305054)
			(stroke
				(width 0.1)
				(type default)
			)
			(layer "F.Fab")
		)
		(pad "1" smd circle
			(at -0.40005 0 90)
			(size 0 0)
			(layers "F.Cu" "F.Mask" "F.Paste")
			(net "P3V3_AUX")
		)
		(pad "2" smd circle
			(at 0.40005 0 90)
			(size 0 0)
			(layers "F.Cu" "F.Mask" "F.Paste")
			(net "GND")
		)
	)
	(footprint ""
		(layer "F.Cu")
		(at 28.321 -194.818 90)
		(property "Reference" "R5517"
			(at 0 0 90)
			(layer "F.SilkS")
			(hide yes)
			(effects
				(font
					(size 1.27 1.27)
				)
			)
		)
		(property "Value" ""
			(at 0 0 90)
			(layer "F.Fab")
			(effects
				(font
					(size 1.27 1.27)
				)
			)
		)
		(duplicate_pad_numbers_are_jumpers no)
		(fp_line
			(start 0.7874 -0.4064)
			(end 0.7874 0.4064)
			(stroke
				(width 0.1524)
				(type default)
			)
			(layer "F.SilkS")
		)
		(fp_line
			(start -0.7874 -0.4064)
			(end 0.7874 -0.4064)
			(stroke
				(width 0.1524)
				(type default)
			)
			(layer "F.SilkS")
		)
		(fp_line
			(start 0.7874 0.4064)
			(end -0.7874 0.4064)
			(stroke
				(width 0.1524)
				(type default)
			)
			(layer "F.SilkS")
		)
		(fp_line
			(start -0.7874 0.4064)
			(end -0.7874 -0.4064)
			(stroke
				(width 0.1524)
				(type default)
			)
			(layer "F.SilkS")
		)
		(fp_line
			(start -0.12065 -0.305054)
			(end -0.12065 -0.2794)
			(stroke
				(width 0.1)
				(type default)
			)
			(layer "F.Fab")
		)
		(fp_line
			(start -0.67945 -0.305054)
			(end -0.12065 -0.305054)
			(stroke
				(width 0.1)
				(type default)
			)
			(layer "F.Fab")
		)
		(fp_line
			(start 0.67945 -0.3048)
			(end 0.67945 0.3048)
			(stroke
				(width 0.1)
				(type default)
			)
			(layer "F.Fab")
		)
		(fp_line
			(start 0.12065 -0.3048)
			(end 0.67945 -0.3048)
			(stroke
				(width 0.1)
				(type default)
			)
			(layer "F.Fab")
		)
		(fp_line
			(start 0.12065 -0.2794)
			(end 0.12065 -0.3048)
			(stroke
				(width 0.1)
				(type default)
			)
			(layer "F.Fab")
		)
		(fp_line
			(start -0.12065 -0.2794)
			(end 0.12065 -0.2794)
			(stroke
				(width 0.1)
				(type default)
			)
			(layer "F.Fab")
		)
		(fp_line
			(start 0.120396 0.2794)
			(end -0.12065 0.2794)
			(stroke
				(width 0.1)
				(type default)
			)
			(layer "F.Fab")
		)
		(fp_line
			(start -0.12065 0.2794)
			(end -0.12065 0.3048)
			(stroke
				(width 0.1)
				(type default)
			)
			(layer "F.Fab")
		)
		(fp_line
			(start 0.67945 0.3048)
			(end 0.120396 0.3048)
			(stroke
				(width 0.1)
				(type default)
			)
			(layer "F.Fab")
		)
		(fp_line
			(start 0.120396 0.3048)
			(end 0.120396 0.2794)
			(stroke
				(width 0.1)
				(type default)
			)
			(layer "F.Fab")
		)
		(fp_line
			(start -0.12065 0.3048)
			(end -0.67945 0.3048)
			(stroke
				(width 0.1)
				(type default)
			)
			(layer "F.Fab")
		)
		(fp_line
			(start -0.67945 0.3048)
			(end -0.67945 -0.305054)
			(stroke
				(width 0.1)
				(type default)
			)
			(layer "F.Fab")
		)
		(pad "1" smd circle
			(at -0.40005 0 90)
			(size 0 0)
			(layers "F.Cu" "F.Mask" "F.Paste")
			(net "P3V3_AUX")
		)
		(pad "2" smd circle
			(at 0.40005 0 90)
			(size 0 0)
			(layers "F.Cu" "F.Mask" "F.Paste")
			(net "FAN_6_PWM_BUF")
		)
	)
	(footprint ""
		(layer "F.Cu")
		(at 37.338 -294.767 180)
		(property "Reference" "R5188"
			(at 0 0 180)
			(layer "F.SilkS")
			(hide yes)
			(effects
				(font
					(size 1.27 1.27)
				)
			)
		)
		(property "Value" ""
			(at 0 0 180)
			(layer "F.Fab")
			(effects
				(font
					(size 1.27 1.27)
				)
			)
		)
		(duplicate_pad_numbers_are_jumpers no)
		(fp_line
			(start 0.7874 0.4064)
			(end -0.7874 0.4064)
			(stroke
				(width 0.1524)
				(type default)
			)
			(layer "F.SilkS")
		)
		(fp_line
			(start 0.7874 -0.4064)
			(end 0.7874 0.4064)
			(stroke
				(width 0.1524)
				(type default)
			)
			(layer "F.SilkS")
		)
		(fp_line
			(start -0.7874 0.4064)
			(end -0.7874 -0.4064)
			(stroke
				(width 0.1524)
				(type default)
			)
			(layer "F.SilkS")
		)
		(fp_line
			(start -0.7874 -0.4064)
			(end 0.7874 -0.4064)
			(stroke
				(width 0.1524)
				(type default)
			)
			(layer "F.SilkS")
		)
		(fp_line
			(start 0.67945 0.3048)
			(end 0.120396 0.3048)
			(stroke
				(width 0.1)
				(type default)
			)
			(layer "F.Fab")
		)
		(fp_line
			(start 0.67945 -0.3048)
			(end 0.67945 0.3048)
			(stroke
				(width 0.1)
				(type default)
			)
			(layer "F.Fab")
		)
		(fp_line
			(start 0.12065 -0.2794)
			(end 0.12065 -0.3048)
			(stroke
				(width 0.1)
				(type default)
			)
			(layer "F.Fab")
		)
		(fp_line
			(start 0.12065 -0.3048)
			(end 0.67945 -0.3048)
			(stroke
				(width 0.1)
				(type default)
			)
			(layer "F.Fab")
		)
		(fp_line
			(start 0.120396 0.3048)
			(end 0.120396 0.2794)
			(stroke
				(width 0.1)
				(type default)
			)
			(layer "F.Fab")
		)
		(fp_line
			(start 0.120396 0.2794)
			(end -0.12065 0.2794)
			(stroke
				(width 0.1)
				(type default)
			)
			(layer "F.Fab")
		)
		(fp_line
			(start -0.12065 0.3048)
			(end -0.67945 0.3048)
			(stroke
				(width 0.1)
				(type default)
			)
			(layer "F.Fab")
		)
		(fp_line
			(start -0.12065 0.2794)
			(end -0.12065 0.3048)
			(stroke
				(width 0.1)
				(type default)
			)
			(layer "F.Fab")
		)
		(fp_line
			(start -0.12065 -0.2794)
			(end 0.12065 -0.2794)
			(stroke
				(width 0.1)
				(type default)
			)
			(layer "F.Fab")
		)
		(fp_line
			(start -0.12065 -0.305054)
			(end -0.12065 -0.2794)
			(stroke
				(width 0.1)
				(type default)
			)
			(layer "F.Fab")
		)
		(fp_line
			(start -0.67945 0.3048)
			(end -0.67945 -0.305054)
			(stroke
				(width 0.1)
				(type default)
			)
			(layer "F.Fab")
		)
		(fp_line
			(start -0.67945 -0.305054)
			(end -0.12065 -0.305054)
			(stroke
				(width 0.1)
				(type default)
			)
			(layer "F.Fab")
		)
		(pad "1" smd circle
			(at -0.40005 0 180)
			(size 0 0)
			(layers "F.Cu" "F.Mask" "F.Paste")
			(net "SMB_FAN0_SDA_R")
		)
		(pad "2" smd circle
			(at 0.40005 0 180)
			(size 0 0)
			(layers "F.Cu" "F.Mask" "F.Paste")
			(net "SMB_FAN0_SDA")
		)
	)
	(footprint ""
		(layer "F.Cu")
		(at 37.846 -198.374 -90)
		(property "Reference" "R5692"
			(at 0 0 270)
			(layer "F.SilkS")
			(hide yes)
			(effects
				(font
					(size 1.27 1.27)
				)
			)
		)
		(property "Value" ""
			(at 0 0 270)
			(layer "F.Fab")
			(effects
				(font
					(size 1.27 1.27)
				)
			)
		)
		(duplicate_pad_numbers_are_jumpers no)
		(fp_line
			(start -0.7874 0.4064)
			(end -0.7874 -0.4064)
			(stroke
				(width 0.1524)
				(type default)
			)
			(layer "F.SilkS")
		)
		(fp_line
			(start 0.7874 0.4064)
			(end -0.7874 0.4064)
			(stroke
				(width 0.1524)
				(type default)
			)
			(layer "F.SilkS")
		)
		(fp_line
			(start -0.7874 -0.4064)
			(end 0.7874 -0.4064)
			(stroke
				(width 0.1524)
				(type default)
			)
			(layer "F.SilkS")
		)
		(fp_line
			(start 0.7874 -0.4064)
			(end 0.7874 0.4064)
			(stroke
				(width 0.1524)
				(type default)
			)
			(layer "F.SilkS")
		)
		(fp_line
			(start -0.67945 0.3048)
			(end -0.67945 -0.305054)
			(stroke
				(width 0.1)
				(type default)
			)
			(layer "F.Fab")
		)
		(fp_line
			(start -0.12065 0.3048)
			(end -0.67945 0.3048)
			(stroke
				(width 0.1)
				(type default)
			)
			(layer "F.Fab")
		)
		(fp_line
			(start 0.120396 0.3048)
			(end 0.120396 0.2794)
			(stroke
				(width 0.1)
				(type default)
			)
			(layer "F.Fab")
		)
		(fp_line
			(start 0.67945 0.3048)
			(end 0.120396 0.3048)
			(stroke
				(width 0.1)
				(type default)
			)
			(layer "F.Fab")
		)
		(fp_line
			(start -0.12065 0.2794)
			(end -0.12065 0.3048)
			(stroke
				(width 0.1)
				(type default)
			)
			(layer "F.Fab")
		)
		(fp_line
			(start 0.120396 0.2794)
			(end -0.12065 0.2794)
			(stroke
				(width 0.1)
				(type default)
			)
			(layer "F.Fab")
		)
		(fp_line
			(start -0.12065 -0.2794)
			(end 0.12065 -0.2794)
			(stroke
				(width 0.1)
				(type default)
			)
			(layer "F.Fab")
		)
		(fp_line
			(start 0.12065 -0.2794)
			(end 0.12065 -0.3048)
			(stroke
				(width 0.1)
				(type default)
			)
			(layer "F.Fab")
		)
		(fp_line
			(start 0.12065 -0.3048)
			(end 0.67945 -0.3048)
			(stroke
				(width 0.1)
				(type default)
			)
			(layer "F.Fab")
		)
		(fp_line
			(start 0.67945 -0.3048)
			(end 0.67945 0.3048)
			(stroke
				(width 0.1)
				(type default)
			)
			(layer "F.Fab")
		)
		(fp_line
			(start -0.67945 -0.305054)
			(end -0.12065 -0.305054)
			(stroke
				(width 0.1)
				(type default)
			)
			(layer "F.Fab")
		)
		(fp_line
			(start -0.12065 -0.305054)
			(end -0.12065 -0.2794)
			(stroke
				(width 0.1)
				(type default)
			)
			(layer "F.Fab")
		)
		(pad "1" smd rect
			(at -0.40005 0 90)
			(size 0.4572 0.508)
			(layers "F.Cu" "F.Mask" "F.Paste")
			(net "P12V_LED_R_FAN1")
		)
		(pad "2" smd rect
			(at 0.40005 0 90)
			(size 0.4572 0.508)
			(layers "F.Cu" "F.Mask" "F.Paste")
			(net "P12V_LED_R1_FAN1")
		)
	)
	(footprint ""
		(layer "F.Cu")
		(at 14.351 -298.069 180)
		(property "Reference" "D257"
			(at 4.826 -0.53467 0)
			(unlocked yes)
			(layer "F.SilkS")
			(effects
				(font
					(size 0.7874 0.5842)
					(thickness 0.1524)
				)
				(justify left)
			)
		)
		(property "Value" ""
			(at 0 0 180)
			(layer "F.Fab")
			(effects
				(font
					(size 1.27 1.27)
				)
			)
		)
		(duplicate_pad_numbers_are_jumpers no)
		(fp_line
			(start 0.94488 0.450088)
			(end 0.94488 -0.450088)
			(stroke
				(width 0.1524)
				(type default)
			)
			(layer "F.SilkS")
		)
		(fp_line
			(start 0.94488 -0.450088)
			(end -0.854964 -0.450088)
			(stroke
				(width 0.1524)
				(type default)
			)
			(layer "F.SilkS")
		)
		(fp_line
			(start 0.870458 -0.2794)
			(end 0.845058 0.4064)
			(stroke
				(width 0.1524)
				(type default)
			)
			(layer "F.SilkS")
		)
		(fp_line
			(start 0.845058 0.4064)
			(end 0.845058 -0.381)
			(stroke
				(width 0.1524)
				(type default)
			)
			(layer "F.SilkS")
		)
		(fp_line
			(start -0.854964 0.450088)
			(end 0.925068 0.450088)
			(stroke
				(width 0.1524)
				(type default)
			)
			(layer "F.SilkS")
		)
		(fp_line
			(start -0.854964 -0.450088)
			(end -0.854964 0.450088)
			(stroke
				(width 0.1524)
				(type default)
			)
			(layer "F.SilkS")
		)
		(fp_line
			(start 0.54991 0.350012)
			(end 0.54991 -0.350012)
			(stroke
				(width 0.1)
				(type default)
			)
			(layer "F.Fab")
		)
		(fp_line
			(start 0.54991 -0.350012)
			(end -0.54991 -0.350012)
			(stroke
				(width 0.1)
				(type default)
			)
			(layer "F.Fab")
		)
		(fp_line
			(start -0.54991 0.350012)
			(end 0.54991 0.350012)
			(stroke
				(width 0.1)
				(type default)
			)
			(layer "F.Fab")
		)
		(fp_line
			(start -0.54991 -0.350012)
			(end -0.54991 0.350012)
			(stroke
				(width 0.1)
				(type default)
			)
			(layer "F.Fab")
		)
		(fp_text user "-"
			(at 2.159 -0.28575 0)
			(unlocked yes)
			(layer "F.SilkS")
			(effects
				(font
					(size 1.905 1.4224)
					(thickness 0.1524)
				)
				(justify left)
			)
		)
		(fp_text user "+"
			(at -0.381 0.88265 0)
			(unlocked yes)
			(layer "F.SilkS")
			(effects
				(font
					(size 1.905 1.4224)
					(thickness 0.1524)
				)
				(justify left)
			)
		)
		(fp_text user "-"
			(at 2.48539 0.239014 0)
			(unlocked yes)
			(layer "F.Fab")
			(effects
				(font
					(size 1.905 1.4224)
					(thickness 0.1524)
				)
				(justify left)
			)
		)
		(fp_text user "+"
			(at -0.808228 0.239014 0)
			(unlocked yes)
			(layer "F.Fab")
			(effects
				(font
					(size 1.905 1.4224)
					(thickness 0.1524)
				)
				(justify left)
			)
		)
		(pad "A" smd rect
			(at -0.424942 0 180)
			(size 0.5588 0.6096)
			(layers "F.Cu" "F.Mask" "F.Paste")
			(net "GND")
		)
		(pad "C" smd rect
			(at 0.424942 0)
			(size 0.5588 0.6096)
			(layers "F.Cu" "F.Mask" "F.Paste")
			(net "FAN_7_FAIL_R_LED_N")
		)
	)
)
